# T6G (Grand Teton) — schematic netlist excerpt (pin names and nets, part order shuffled) for the footprints in the layout excerpt that follows; sources: Cadence DE-HDL packaged netlist, KiCad conversion of 04192023_DAF0TMB3IC0_F0TG_MB_C_brd_V02_OCP.brd

PL78  Q_INDUCTOR  1.0UH/18A IND  pkg SMLF  page 209 : \1\ = SW_PVDD18_S5_P0_SW ; \2\ = PVDD18_S5_P0
PC6620  Q_CAP  0.1UF 25V 10% X7R  pkg 0402  page 365 : A = P12V_AUX ; B = GND
C1787  Q_CAP  0.1UF 16V 10% X7R  pkg C0402  page 267 : A = P3V3_AUX ; B = GND

(kicad_pcb
	(version 20260206)
	(generator "pcbnew")
	(generator_version "10.0")
	(general
		(thickness 1.6)
		(legacy_teardrops no)
	)
	(paper "A4")
	(title_block
		(title "04192023_DAF0TMB3IC0_F0TG_MB_C_brd_V02_OCP.brd")
		(comment 1 "Grand Teton / footprints 3034-3036 of 8354")
	)
	(layers
		(0 "F.Cu" signal "TOP")
		(4 "In1.Cu" signal "GND")
		(6 "In2.Cu" signal "IN1")
		(8 "In3.Cu" signal "GND1")
		(10 "In4.Cu" signal "IN2")
		(12 "In5.Cu" signal "GND2")
		(14 "In6.Cu" signal "IN3")
		(16 "In7.Cu" signal "GND3")
		(18 "In8.Cu" signal "VCC")
		(20 "In9.Cu" signal "VCC1")
		(22 "In10.Cu" signal "GND4")
		(24 "In11.Cu" signal "IN4")
		(26 "In12.Cu" signal "GND5")
		(28 "In13.Cu" signal "IN5")
		(30 "In14.Cu" signal "GND6")
		(32 "In15.Cu" signal "IN6")
		(34 "In16.Cu" signal "GND7")
		(2 "B.Cu" signal "BOTTOM")
		(9 "F.Adhes" user "F.Adhesive")
		(11 "B.Adhes" user "B.Adhesive")
		(13 "F.Paste" user "Package Geometry/Pastemask Top")
		(15 "B.Paste" user "Package Geometry/Pastemask Bottom")
		(5 "F.SilkS" user "Ref Des/Silkscreen Top")
		(7 "B.SilkS" user "Ref Des/Silkscreen Bottom")
		(1 "F.Mask" user "Board Geometry/Soldermask Top")
		(3 "B.Mask" user "Board Geometry/Soldermask Bottom")
		(17 "Dwgs.User" user "User.Drawings")
		(19 "Cmts.User" user "User.Comments")
		(21 "Eco1.User" user "User.Eco1")
		(23 "Eco2.User" user "User.Eco2")
		(25 "Edge.Cuts" user "Board Geometry/Outline")
		(27 "Margin" user)
		(31 "F.CrtYd" user "Package Geometry/Place Bound Top")
		(29 "B.CrtYd" user "Package Geometry/Place Bound Bottom")
		(35 "F.Fab" user "Ref Des/Assembly Top")
		(33 "B.Fab" user "Ref Des/Assembly Bottom")
	)
	(footprint ""
		(layer "F.Cu")
		(at 287.339024 -398.913858 90)
		(property "Reference" "C1787"
			(at 0 0 90)
			(layer "F.SilkS")
			(hide yes)
			(effects
				(font
					(size 1.27 1.27)
				)
			)
		)
		(property "Value" ""
			(at 0 0 90)
			(layer "F.Fab")
			(effects
				(font
					(size 1.27 1.27)
				)
			)
		)
		(duplicate_pad_numbers_are_jumpers no)
		(fp_line
			(start 0.7874 -0.4064)
			(end 0.7874 0.4064)
			(stroke
				(width 0.1524)
				(type default)
			)
			(layer "F.SilkS")
		)
		(fp_line
			(start -0.7874 -0.4064)
			(end 0.7874 -0.4064)
			(stroke
				(width 0.1524)
				(type default)
			)
			(layer "F.SilkS")
		)
		(fp_line
			(start 0.7874 0.4064)
			(end -0.7874 0.4064)
			(stroke
				(width 0.1524)
				(type default)
			)
			(layer "F.SilkS")
		)
		(fp_line
			(start -0.7874 0.4064)
			(end -0.7874 -0.4064)
			(stroke
				(width 0.1524)
				(type default)
			)
			(layer "F.SilkS")
		)
		(fp_line
			(start -0.12065 -0.305054)
			(end -0.12065 -0.2794)
			(stroke
				(width 0.1)
				(type default)
			)
			(layer "F.Fab")
		)
		(fp_line
			(start -0.67945 -0.305054)
			(end -0.12065 -0.305054)
			(stroke
				(width 0.1)
				(type default)
			)
			(layer "F.Fab")
		)
		(fp_line
			(start 0.67945 -0.3048)
			(end 0.67945 0.3048)
			(stroke
				(width 0.1)
				(type default)
			)
			(layer "F.Fab")
		)
		(fp_line
			(start 0.12065 -0.3048)
			(end 0.67945 -0.3048)
			(stroke
				(width 0.1)
				(type default)
			)
			(layer "F.Fab")
		)
		(fp_line
			(start 0.12065 -0.2794)
			(end 0.12065 -0.3048)
			(stroke
				(width 0.1)
				(type default)
			)
			(layer "F.Fab")
		)
		(fp_line
			(start -0.12065 -0.2794)
			(end 0.12065 -0.2794)
			(stroke
				(width 0.1)
				(type default)
			)
			(layer "F.Fab")
		)
		(fp_line
			(start 0.120396 0.2794)
			(end -0.12065 0.2794)
			(stroke
				(width 0.1)
				(type default)
			)
			(layer "F.Fab")
		)
		(fp_line
			(start -0.12065 0.2794)
			(end -0.12065 0.3048)
			(stroke
				(width 0.1)
				(type default)
			)
			(layer "F.Fab")
		)
		(fp_line
			(start 0.67945 0.3048)
			(end 0.120396 0.3048)
			(stroke
				(width 0.1)
				(type default)
			)
			(layer "F.Fab")
		)
		(fp_line
			(start 0.120396 0.3048)
			(end 0.120396 0.2794)
			(stroke
				(width 0.1)
				(type default)
			)
			(layer "F.Fab")
		)
		(fp_line
			(start -0.12065 0.3048)
			(end -0.67945 0.3048)
			(stroke
				(width 0.1)
				(type default)
			)
			(layer "F.Fab")
		)
		(fp_line
			(start -0.67945 0.3048)
			(end -0.67945 -0.305054)
			(stroke
				(width 0.1)
				(type default)
			)
			(layer "F.Fab")
		)
		(pad "1" smd circle
			(at -0.40005 0 90)
			(size 0 0)
			(layers "F.Cu" "F.Mask" "F.Paste")
			(net "P3V3_AUX")
		)
		(pad "2" smd circle
			(at 0.40005 0 90)
			(size 0 0)
			(layers "F.Cu" "F.Mask" "F.Paste")
			(net "GND")
		)
	)
	(footprint ""
		(layer "F.Cu")
		(at 26.947622 -405.840438)
		(property "Reference" "PC6620"
			(at 0 0 0)
			(layer "F.SilkS")
			(hide yes)
			(effects
				(font
					(size 1.27 1.27)
				)
			)
		)
		(property "Value" ""
			(at 0 0 0)
			(layer "F.Fab")
			(effects
				(font
					(size 1.27 1.27)
				)
			)
		)
		(duplicate_pad_numbers_are_jumpers no)
		(fp_line
			(start -0.7874 -0.4064)
			(end 0.7874 -0.4064)
			(stroke
				(width 0.1524)
				(type default)
			)
			(layer "F.SilkS")
		)
		(fp_line
			(start -0.7874 0.4064)
			(end -0.7874 -0.4064)
			(stroke
				(width 0.1524)
				(type default)
			)
			(layer "F.SilkS")
		)
		(fp_line
			(start 0.7874 -0.4064)
			(end 0.7874 0.4064)
			(stroke
				(width 0.1524)
				(type default)
			)
			(layer "F.SilkS")
		)
		(fp_line
			(start 0.7874 0.4064)
			(end -0.7874 0.4064)
			(stroke
				(width 0.1524)
				(type default)
			)
			(layer "F.SilkS")
		)
		(fp_line
			(start -0.67945 -0.305054)
			(end -0.12065 -0.305054)
			(stroke
				(width 0.1)
				(type default)
			)
			(layer "F.Fab")
		)
		(fp_line
			(start -0.67945 0.3048)
			(end -0.67945 -0.305054)
			(stroke
				(width 0.1)
				(type default)
			)
			(layer "F.Fab")
		)
		(fp_line
			(start -0.12065 -0.305054)
			(end -0.12065 -0.2794)
			(stroke
				(width 0.1)
				(type default)
			)
			(layer "F.Fab")
		)
		(fp_line
			(start -0.12065 -0.2794)
			(end 0.12065 -0.2794)
			(stroke
				(width 0.1)
				(type default)
			)
			(layer "F.Fab")
		)
		(fp_line
			(start -0.12065 0.2794)
			(end -0.12065 0.3048)
			(stroke
				(width 0.1)
				(type default)
			)
			(layer "F.Fab")
		)
		(fp_line
			(start -0.12065 0.3048)
			(end -0.67945 0.3048)
			(stroke
				(width 0.1)
				(type default)
			)
			(layer "F.Fab")
		)
		(fp_line
			(start 0.120396 0.2794)
			(end -0.12065 0.2794)
			(stroke
				(width 0.1)
				(type default)
			)
			(layer "F.Fab")
		)
		(fp_line
			(start 0.120396 0.3048)
			(end 0.120396 0.2794)
			(stroke
				(width 0.1)
				(type default)
			)
			(layer "F.Fab")
		)
		(fp_line
			(start 0.12065 -0.3048)
			(end 0.67945 -0.3048)
			(stroke
				(width 0.1)
				(type default)
			)
			(layer "F.Fab")
		)
		(fp_line
			(start 0.12065 -0.2794)
			(end 0.12065 -0.3048)
			(stroke
				(width 0.1)
				(type default)
			)
			(layer "F.Fab")
		)
		(fp_line
			(start 0.67945 -0.3048)
			(end 0.67945 0.3048)
			(stroke
				(width 0.1)
				(type default)
			)
			(layer "F.Fab")
		)
		(fp_line
			(start 0.67945 0.3048)
			(end 0.120396 0.3048)
			(stroke
				(width 0.1)
				(type default)
			)
			(layer "F.Fab")
		)
		(pad "1" smd circle
			(at -0.40005 0)
			(size 0 0)
			(layers "F.Cu" "F.Mask" "F.Paste")
			(net "P12V_AUX")
		)
		(pad "2" smd circle
			(at 0.40005 0)
			(size 0 0)
			(layers "F.Cu" "F.Mask" "F.Paste")
			(net "GND")
		)
	)
	(footprint ""
		(layer "F.Cu")
		(at 335.82991 -150.686262 90)
		(property "Reference" "PL78"
			(at -5.08 -5.81533 90)
			(unlocked yes)
			(layer "F.SilkS")
			(effects
				(font
					(size 0.7874 0.5842)
					(thickness 0.1524)
				)
				(justify left)
			)
		)
		(property "Value" ""
			(at 0 0 90)
			(layer "F.Fab")
			(effects
				(font
					(size 1.27 1.27)
				)
			)
		)
		(duplicate_pad_numbers_are_jumpers no)
		(fp_line
			(start 5.1054 -5.100066)
			(end -5.1054 -5.100066)
			(stroke
				(width 0.1524)
				(type default)
			)
			(layer "F.SilkS")
		)
		(fp_line
			(start -5.1054 -5.100066)
			(end -5.1054 -1.8796)
			(stroke
				(width 0.1524)
				(type default)
			)
			(layer "F.SilkS")
		)
		(fp_line
			(start 5.1054 -1.8796)
			(end 5.1054 -5.100066)
			(stroke
				(width 0.1524)
				(type default)
			)
			(layer "F.SilkS")
		)
		(fp_line
			(start -5.1054 1.8796)
			(end -5.1054 5.100066)
			(stroke
				(width 0.1524)
				(type default)
			)
			(layer "F.SilkS")
		)
		(fp_line
			(start 5.1054 5.100066)
			(end 5.1054 1.8796)
			(stroke
				(width 0.1524)
				(type default)
			)
			(layer "F.SilkS")
		)
		(fp_line
			(start -5.1054 5.100066)
			(end 5.1054 5.100066)
			(stroke
				(width 0.1524)
				(type default)
			)
			(layer "F.SilkS")
		)
		(fp_line
			(start 5.1054 -5.100066)
			(end 5.1054 5.100066)
			(stroke
				(width 0.1)
				(type default)
			)
			(layer "F.Fab")
		)
		(fp_line
			(start -5.1054 -5.100066)
			(end 5.1054 -5.100066)
			(stroke
				(width 0.1)
				(type default)
			)
			(layer "F.Fab")
		)
		(fp_line
			(start 5.1054 5.100066)
			(end -5.1054 5.100066)
			(stroke
				(width 0.1)
				(type default)
			)
			(layer "F.Fab")
		)
		(fp_line
			(start -5.1054 5.100066)
			(end -5.1054 -5.100066)
			(stroke
				(width 0.1)
				(type default)
			)
			(layer "F.Fab")
		)
		(pad "1" smd rect
			(at -3.999992 0 90)
			(size 3.5052 3.5052)
			(layers "F.Cu" "F.Mask" "F.Paste")
			(net "SW_PVDD18_S5_P0_SW")
		)
		(pad "2" smd rect
			(at 3.999992 0 90)
			(size 3.5052 3.5052)
			(layers "F.Cu" "F.Mask" "F.Paste")
			(net "PVDD18_S5_P0")
		)
	)
)
